(kicad_pcb
	(version 20260206)
	(generator "pcbnew")
	(generator_version "10.0")
	(general
		(thickness 1.6)
		(legacy_teardrops no)
	)
	(paper "A4")
	(title_block
		(title "baseboard — 13948-1b.1110WZS1818.brd")
		(comment 1 "Honey Badger (Wiwynn) / footprints 692-696 of 2523")
	)
	(layers
		(0 "F.Cu" signal "TOP")
		(4 "In1.Cu" signal "L2GND")
		(6 "In2.Cu" signal "L3")
		(8 "In3.Cu" signal "L4VCC")
		(10 "In4.Cu" signal "L5VCC")
		(12 "In5.Cu" signal "L6")
		(14 "In6.Cu" signal "L7GND")
		(2 "B.Cu" signal "BOTTOM")
		(9 "F.Adhes" user "F.Adhesive")
		(11 "B.Adhes" user "B.Adhesive")
		(13 "F.Paste" user "Package Geometry/Pastemask Top")
		(15 "B.Paste" user "Package Geometry/Pastemask Bottom")
		(5 "F.SilkS" user "Ref Des/Silkscreen Top")
		(7 "B.SilkS" user "Ref Des/Silkscreen Bottom")
		(1 "F.Mask" user "Board Geometry/Soldermask Top")
		(3 "B.Mask" user "Board Geometry/Soldermask Bottom")
		(17 "Dwgs.User" user "User.Drawings")
		(19 "Cmts.User" user "User.Comments")
		(21 "Eco1.User" user "User.Eco1")
		(23 "Eco2.User" user "User.Eco2")
		(25 "Edge.Cuts" user "Board Geometry/Outline")
		(27 "Margin" user)
		(31 "F.CrtYd" user "Package Geometry/Place Bound Top")
		(29 "B.CrtYd" user "Package Geometry/Place Bound Bottom")
		(35 "F.Fab" user "Ref Des/Assembly Top")
		(33 "B.Fab" user "Ref Des/Assembly Bottom")
	)
	(footprint ""
		(layer "F.Cu")
		(at 171.131992 -16.129 -90)
		(property "Reference" "R420"
			(at 0 0 270)
			(layer "F.SilkS")
			(hide yes)
			(effects
				(font
					(size 1.27 1.27)
				)
			)
		)
		(property "Value" "150R3J-L-GP"
			(at -0.0254 -2.5146 270)
			(unlocked yes)
			(layer "F.Fab")
			(hide yes)
			(effects
				(font
					(size 1.016 1.016)
					(thickness 0.1524)
				)
			)
		)
		(property "Device Type" "R603H22"
			(at -0.0254 -4.0386 270)
			(unlocked yes)
			(layer "F.Fab")
			(hide yes)
			(effects
				(font
					(size 1.016 1.016)
					(thickness 0.1524)
				)
			)
		)
		(duplicate_pad_numbers_are_jumpers no)
		(fp_line
			(start -0.4826 0)
			(end -0.2032 0)
			(stroke
				(width 0.2032)
				(type default)
			)
			(layer "F.SilkS")
		)
		(fp_line
			(start 0.2032 0)
			(end 0.4826 0)
			(stroke
				(width 0.2032)
				(type default)
			)
			(layer "F.SilkS")
		)
		(fp_rect
			(start -0.5842 1.3335)
			(end 0.5842 -1.3335)
			(stroke
				(width 0)
				(type default)
			)
			(fill no)
			(layer "F.CrtYd")
		)
		(fp_rect
			(start -0.5842 1.3335)
			(end 0.5842 -1.3335)
			(stroke
				(width 0)
				(type default)
			)
			(fill no)
			(layer "F.Fab")
		)
		(pad "1" smd custom
			(at 0 -0.762 270)
			(size 0.2159 0.2159)
			(layers "F.Cu" "F.Mask" "F.Paste")
			(net "P3V3_STBY")
			(options
				(clearance outline)
				(anchor circle)
			)
			(primitives
				(gr_poly
					(pts
						(arc
							(start -0.3302 -0.4318)
							(mid -0.402042 -0.402042)
							(end -0.4318 -0.3302)
						)
						(arc
							(start -0.4318 0.3302)
							(mid -0.402042 0.402042)
							(end -0.3302 0.4318)
						)
						(arc
							(start 0.3302 0.4318)
							(mid 0.402042 0.402042)
							(end 0.4318 0.3302)
						)
						(arc
							(start 0.4318 -0.3302)
							(mid 0.402042 -0.402042)
							(end 0.3302 -0.4318)
						)
					)
					(width 0)
					(fill yes)
				)
			)
		)
		(pad "2" smd custom
			(at 0 0.762 270)
			(size 0.2159 0.2159)
			(layers "F.Cu" "F.Mask" "F.Paste")
			(net "LED_MDI0_ACT")
			(options
				(clearance outline)
				(anchor circle)
			)
			(primitives
				(gr_poly
					(pts
						(arc
							(start -0.3302 -0.4318)
							(mid -0.402042 -0.402042)
							(end -0.4318 -0.3302)
						)
						(arc
							(start -0.4318 0.3302)
							(mid -0.402042 0.402042)
							(end -0.3302 0.4318)
						)
						(arc
							(start 0.3302 0.4318)
							(mid 0.402042 0.402042)
							(end 0.4318 0.3302)
						)
						(arc
							(start 0.4318 -0.3302)
							(mid 0.402042 -0.402042)
							(end 0.3302 -0.4318)
						)
					)
					(width 0)
					(fill yes)
				)
			)
		)
	)
	(footprint ""
		(layer "F.Cu")
		(at 104.950006 -5.999988 180)
		(property "Reference" "Q4"
			(at 0 0 180)
			(layer "F.SilkS")
			(hide yes)
			(effects
				(font
					(size 1.27 1.27)
				)
			)
		)
		(property "Value" "MPS2907ARLRAG-GP"
			(at 5.0419 -5.5372 180)
			(unlocked yes)
			(layer "F.Fab")
			(hide yes)
			(effects
				(font
					(size 1.016 1.016)
					(thickness 0.1524)
				)
			)
		)
		(property "Device Type" "TO-92-CBE-5737H368"
			(at 5.0419 -7.0612 180)
			(unlocked yes)
			(layer "F.Fab")
			(hide yes)
			(effects
				(font
					(size 1.016 1.016)
					(thickness 0.1524)
				)
			)
		)
		(duplicate_pad_numbers_are_jumpers no)
		(fp_line
			(start 3.429 0.8255)
			(end 2.518664 0.8255)
			(stroke
				(width 0.1524)
				(type default)
			)
			(layer "F.SilkS")
		)
		(fp_line
			(start 3.429 -0.8255)
			(end 3.429 0.8255)
			(stroke
				(width 0.1524)
				(type default)
			)
			(layer "F.SilkS")
		)
		(fp_line
			(start 2.551938 -0.8255)
			(end 3.429 -0.8255)
			(stroke
				(width 0.1524)
				(type default)
			)
			(layer "F.SilkS")
		)
		(fp_line
			(start -2.170684 -1.6002)
			(end 2.170684 -1.6002)
			(stroke
				(width 0.1524)
				(type default)
			)
			(layer "F.SilkS")
		)
		(fp_line
			(start -2.518664 0.8255)
			(end -3.429 0.8255)
			(stroke
				(width 0.1524)
				(type default)
			)
			(layer "F.SilkS")
		)
		(fp_line
			(start -3.429 0.8255)
			(end -3.429 -0.8255)
			(stroke
				(width 0.1524)
				(type default)
			)
			(layer "F.SilkS")
		)
		(fp_line
			(start -3.429 -0.8255)
			(end -2.551938 -0.8255)
			(stroke
				(width 0.1524)
				(type default)
			)
			(layer "F.SilkS")
		)
		(fp_arc
			(start 2.533396 -0.883666)
			(mid 2.542832 -0.854636)
			(end 2.551938 -0.8255)
			(stroke
				(width 0.1524)
				(type default)
			)
			(layer "F.SilkS")
		)
		(fp_arc
			(start 2.521204 -0.92075)
			(mid 2.527368 -0.90223)
			(end 2.533396 -0.883666)
			(stroke
				(width 0.1524)
				(type default)
			)
			(layer "F.SilkS")
		)
		(fp_arc
			(start 2.518664 0.8255)
			(mid 0 2.615953)
			(end -2.518664 0.8255)
			(stroke
				(width 0.1524)
				(type default)
			)
			(layer "F.SilkS")
		)
		(fp_arc
			(start 2.170684 -1.6002)
			(mid 2.370425 -1.273104)
			(end 2.521204 -0.92075)
			(stroke
				(width 0.1524)
				(type default)
			)
			(layer "F.SilkS")
		)
		(fp_arc
			(start -2.521204 -0.92075)
			(mid -2.370409 -1.273096)
			(end -2.170684 -1.6002)
			(stroke
				(width 0.1524)
				(type default)
			)
			(layer "F.SilkS")
		)
		(fp_arc
			(start -2.533396 -0.883666)
			(mid -2.527368 -0.90223)
			(end -2.521204 -0.92075)
			(stroke
				(width 0.1524)
				(type default)
			)
			(layer "F.SilkS")
		)
		(fp_arc
			(start -2.551938 -0.8255)
			(mid -2.542834 -0.854636)
			(end -2.533396 -0.883666)
			(stroke
				(width 0.1524)
				(type default)
			)
			(layer "F.SilkS")
		)
		(fp_poly
			(pts
				(arc
					(start 2.396744 0.2286)
					(mid 0 2.362175)
					(end -2.396744 0.2286)
				)
				(xy -2.8321 0.2286) (xy -2.8321 -0.2286)
				(arc
					(start -2.406396 -0.2286)
					(mid -2.366841 -0.520127)
					(end -2.292096 -0.804672)
				)
				(arc
					(start -2.28092 -0.8382)
					(mid -2.17326 -1.099387)
					(end -2.03581 -1.3462)
				)
				(arc
					(start 2.03581 -1.3462)
					(mid 2.173258 -1.099386)
					(end 2.28092 -0.8382)
				)
				(arc
					(start 2.292096 -0.804672)
					(mid 2.366834 -0.520126)
					(end 2.406396 -0.2286)
				)
				(xy 2.8321 -0.2286) (xy 2.8321 0.2286)
			)
			(stroke
				(width 0)
				(type default)
			)
			(fill no)
			(layer "F.CrtYd")
		)
		(fp_poly
			(pts
				(arc
					(start 2.693162 1.0795)
					(mid 0 2.869936)
					(end -2.693162 1.0795)
				)
				(xy -3.683 1.0795) (xy -3.683 -1.0795)
				(arc
					(start -2.733802 -1.0795)
					(mid -2.545381 -1.483534)
					(end -2.297684 -1.8542)
				)
				(xy 0.6223 -1.8542) (xy 0.6223 -1.346454)
				(arc
					(start -2.036064 -1.346454)
					(mid -2.173513 -1.099511)
					(end -2.281174 -0.8382)
				)
				(arc
					(start -2.29235 -0.804672)
					(mid -2.367086 -0.520253)
					(end -2.40665 -0.228854)
				)
				(xy -2.832354 -0.228854) (xy -2.832354 0.228854)
				(arc
					(start -2.396998 0.228854)
					(mid 0 2.362456)
					(end 2.396998 0.228854)
				)
				(xy 2.832354 0.228854) (xy 2.832354 -0.228854)
				(arc
					(start 2.40665 -0.228854)
					(mid 2.367063 -0.520249)
					(end 2.29235 -0.804672)
				)
				(arc
					(start 2.281174 -0.8382)
					(mid 2.173536 -1.099521)
					(end 2.036064 -1.346454)
				)
				(xy 0.635 -1.346454) (xy 0.635 -1.8542)
				(arc
					(start 2.297684 -1.8542)
					(mid 2.545396 -1.483542)
					(end 2.733802 -1.0795)
				)
				(xy 3.683 -1.0795) (xy 3.683 1.0795)
			)
			(stroke
				(width 0)
				(type default)
			)
			(fill no)
			(layer "F.CrtYd")
		)
		(fp_poly
			(pts
				(arc
					(start 2.693162 1.0795)
					(mid 0 2.869936)
					(end -2.693162 1.0795)
				)
				(xy -3.683 1.0795) (xy -3.683 -1.0795)
				(arc
					(start -2.733802 -1.0795)
					(mid -2.545381 -1.483534)
					(end -2.297684 -1.8542)
				)
				(arc
					(start 2.297684 -1.8542)
					(mid 2.545396 -1.483542)
					(end 2.733802 -1.0795)
				)
				(xy 3.683 -1.0795) (xy 3.683 1.0795)
			)
			(stroke
				(width 0)
				(type default)
			)
			(fill no)
			(layer "F.Fab")
		)
		(pad "B" thru_hole circle
			(at 0 0 180)
			(size 1.143 1.143)
			(drill 0.7874)
			(layers "*.Cu" "*.Mask")
			(remove_unused_layers no)
			(net "TEMP_SENSOR_DXN_BJT")
			(clearance 0.1778)
			(thermal_gap 0.1778)
		)
		(pad "C" thru_hole circle
			(at -2.599944 0 180)
			(size 1.143 1.143)
			(drill 0.7874)
			(layers "*.Cu" "*.Mask")
			(remove_unused_layers no)
			(net "TEMP_SENSOR_C")
			(clearance 0.1778)
			(thermal_gap 0.1778)
		)
		(pad "E" thru_hole circle
			(at 2.599944 0 180)
			(size 1.143 1.143)
			(drill 0.7874)
			(layers "*.Cu" "*.Mask")
			(remove_unused_layers no)
			(net "TEMP_SENSOR_DXP_R")
			(clearance 0.1778)
			(thermal_gap 0.1778)
		)
	)
	(footprint ""
		(layer "F.Cu")
		(at 278.257 -111.887 180)
		(property "Reference" "PQ5"
			(at 0 0 180)
			(layer "F.SilkS")
			(hide yes)
			(effects
				(font
					(size 1.27 1.27)
				)
			)
		)
		(property "Value" "2N7002A-7-GP"
			(at 0.127 -8.9662 180)
			(unlocked yes)
			(layer "F.Fab")
			(hide yes)
			(effects
				(font
					(size 1.016 1.016)
					(thickness 0.1524)
				)
			)
		)
		(property "Device Type" "SOT23DGS2D4H48"
			(at 0.127 -10.4902 180)
			(unlocked yes)
			(layer "F.Fab")
			(hide yes)
			(effects
				(font
					(size 1.016 1.016)
					(thickness 0.1524)
				)
			)
		)
		(duplicate_pad_numbers_are_jumpers no)
		(fp_line
			(start 1.651 1.778)
			(end 1.651 -1.778)
			(stroke
				(width 0.1524)
				(type default)
			)
			(layer "F.SilkS")
		)
		(fp_line
			(start 1.651 -1.778)
			(end -1.651 -1.778)
			(stroke
				(width 0.1524)
				(type default)
			)
			(layer "F.SilkS")
		)
		(fp_line
			(start -1.651 1.778)
			(end 1.651 1.778)
			(stroke
				(width 0.1524)
				(type default)
			)
			(layer "F.SilkS")
		)
		(fp_line
			(start -1.651 -1.778)
			(end -1.651 1.778)
			(stroke
				(width 0.1524)
				(type default)
			)
			(layer "F.SilkS")
		)
		(fp_poly
			(pts
				(xy -1.778 1.8796) (xy -1.778 -1.8796) (xy 1.778 -1.8796) (xy 1.778 1.8796)
			)
			(stroke
				(width 0)
				(type default)
			)
			(fill no)
			(layer "F.CrtYd")
		)
		(fp_poly
			(pts
				(xy -1.778 1.8796) (xy -1.778 -1.8796) (xy 1.778 -1.8796) (xy 1.778 1.8796)
			)
			(stroke
				(width 0)
				(type default)
			)
			(fill no)
			(layer "F.Fab")
		)
		(pad "D" smd custom
			(at 0 -0.9525 180)
			(size 0.1905 0.1905)
			(layers "F.Cu" "F.Mask" "F.Paste")
			(net "P1V8_C_EN_LV")
			(options
				(clearance outline)
				(anchor circle)
			)
			(primitives
				(gr_poly
					(pts
						(arc
							(start -0.1778 0.5715)
							(mid -0.321484 0.511984)
							(end -0.381 0.3683)
						)
						(arc
							(start -0.381 -0.3683)
							(mid -0.321484 -0.511984)
							(end -0.1778 -0.5715)
						)
						(arc
							(start 0.1778 -0.5715)
							(mid 0.321484 -0.511984)
							(end 0.381 -0.3683)
						)
						(arc
							(start 0.381 0.3683)
							(mid 0.321484 0.511984)
							(end 0.1778 0.5715)
						)
					)
					(width 0)
					(fill yes)
				)
			)
		)
		(pad "G" smd custom
			(at -0.98425 0.9525 180)
			(size 0.1905 0.1905)
			(layers "F.Cu" "F.Mask" "F.Paste")
			(net "P1V8_C_EN_G")
			(options
				(clearance outline)
				(anchor circle)
			)
			(primitives
				(gr_poly
					(pts
						(arc
							(start -0.1778 0.5715)
							(mid -0.321484 0.511984)
							(end -0.381 0.3683)
						)
						(arc
							(start -0.381 -0.3683)
							(mid -0.321484 -0.511984)
							(end -0.1778 -0.5715)
						)
						(arc
							(start 0.1778 -0.5715)
							(mid 0.321484 -0.511984)
							(end 0.381 -0.3683)
						)
						(arc
							(start 0.381 0.3683)
							(mid 0.321484 0.511984)
							(end 0.1778 0.5715)
						)
					)
					(width 0)
					(fill yes)
				)
			)
		)
		(pad "S" smd custom
			(at 0.98425 0.9525 180)
			(size 0.1905 0.1905)
			(layers "F.Cu" "F.Mask" "F.Paste")
			(net "P1V8_C_EN_B")
			(options
				(clearance outline)
				(anchor circle)
			)
			(primitives
				(gr_poly
					(pts
						(arc
							(start -0.1778 0.5715)
							(mid -0.321484 0.511984)
							(end -0.381 0.3683)
						)
						(arc
							(start -0.381 -0.3683)
							(mid -0.321484 -0.511984)
							(end -0.1778 -0.5715)
						)
						(arc
							(start 0.1778 -0.5715)
							(mid 0.321484 -0.511984)
							(end 0.381 -0.3683)
						)
						(arc
							(start 0.381 0.3683)
							(mid 0.321484 0.511984)
							(end 0.1778 0.5715)
						)
					)
					(width 0)
					(fill yes)
				)
			)
		)
	)
	(footprint ""
		(layer "F.Cu")
		(at 307.086 -199.136)
		(property "Reference" "U12"
			(at 0 0 0)
			(layer "F.SilkS")
			(hide yes)
			(effects
				(font
					(size 1.27 1.27)
				)
			)
		)
		(property "Value" "PCA9550DP-1-GP"
			(at 0 -13.1572 0)
			(unlocked yes)
			(layer "F.Fab")
			(hide yes)
			(effects
				(font
					(size 1.016 1.016)
					(thickness 0.1524)
				)
			)
		)
		(property "Device Type" "SSOIC8-2H44"
			(at 0 -15.1892 0)
			(unlocked yes)
			(layer "F.Fab")
			(hide yes)
			(effects
				(font
					(size 1.016 1.016)
					(thickness 0.1524)
				)
			)
		)
		(duplicate_pad_numbers_are_jumpers no)
		(fp_line
			(start -1.9304 -1.016)
			(end 1.0922 -1.016)
			(stroke
				(width 0.1524)
				(type default)
			)
			(layer "F.SilkS")
		)
		(fp_line
			(start -1.9304 1.016)
			(end -1.9304 -1.016)
			(stroke
				(width 0.1524)
				(type default)
			)
			(layer "F.SilkS")
		)
		(fp_line
			(start -1.7018 1.0414)
			(end -1.7018 2.9718)
			(stroke
				(width 0.635)
				(type default)
			)
			(layer "F.SilkS")
		)
		(fp_line
			(start -1.524 0)
			(end -1.9304 -0.4064)
			(stroke
				(width 0.1524)
				(type default)
			)
			(layer "F.SilkS")
		)
		(fp_line
			(start -1.524 0)
			(end -1.9304 0.4064)
			(stroke
				(width 0.1524)
				(type default)
			)
			(layer "F.SilkS")
		)
		(fp_line
			(start 1.0922 -1.016)
			(end 1.0922 1.016)
			(stroke
				(width 0.1524)
				(type default)
			)
			(layer "F.SilkS")
		)
		(fp_line
			(start 1.0922 1.016)
			(end -1.9304 1.016)
			(stroke
				(width 0.1524)
				(type default)
			)
			(layer "F.SilkS")
		)
		(fp_poly
			(pts
				(xy -1.1938 -1.016) (xy 1.0922 -1.016) (xy 1.0922 1.016) (xy -1.1938 1.016)
			)
			(stroke
				(width 0)
				(type default)
			)
			(fill yes)
			(layer "F.SilkS")
		)
		(fp_rect
			(start -2.0066 3.3401)
			(end 2.0066 -3.3401)
			(stroke
				(width 0)
				(type default)
			)
			(fill no)
			(layer "F.CrtYd")
		)
		(fp_poly
			(pts
				(xy -2.0066 -3.3401) (xy 2.0066 -3.3401) (xy 2.0066 3.3401) (xy -2.0066 3.3401)
			)
			(stroke
				(width 0)
				(type default)
			)
			(fill no)
			(layer "F.Fab")
		)
		(pad "1" smd rect
			(at -0.97536 2.0701)
			(size 0.4064 1.524)
			(layers "F.Cu" "F.Mask" "F.Paste")
			(net "LED_DR_A0")
		)
		(pad "2" smd rect
			(at -0.32512 2.0701)
			(size 0.4064 1.524)
			(layers "F.Cu" "F.Mask" "F.Paste")
			(net "LED_DR_LED0")
		)
		(pad "3" smd rect
			(at 0.32512 2.0701)
			(size 0.4064 1.524)
			(layers "F.Cu" "F.Mask" "F.Paste")
			(net "LED_DR_LED1")
		)
		(pad "4" smd rect
			(at 0.97536 2.0701)
			(size 0.4064 1.524)
			(layers "F.Cu" "F.Mask" "F.Paste")
			(net "GND")
		)
		(pad "5" smd rect
			(at 0.97536 -2.0701)
			(size 0.4064 1.524)
			(layers "F.Cu" "F.Mask" "F.Paste")
			(net "LED_DR_RESET#")
		)
		(pad "6" smd rect
			(at 0.32512 -2.0701)
			(size 0.4064 1.524)
			(layers "F.Cu" "F.Mask" "F.Paste")
			(net "LED_DR_I2C_SCL")
		)
		(pad "7" smd rect
			(at -0.32512 -2.0701)
			(size 0.4064 1.524)
			(layers "F.Cu" "F.Mask" "F.Paste")
			(net "LED_DR_I2C_SDA")
		)
		(pad "8" smd rect
			(at -0.97536 -2.0701)
			(size 0.4064 1.524)
			(layers "F.Cu" "F.Mask" "F.Paste")
			(net "P3V3_STBY")
		)
	)
	(footprint ""
		(layer "F.Cu")
		(at 131.318 -87.249 90)
		(property "Reference" "SC1262"
			(at 0 0 90)
			(layer "F.SilkS")
			(hide yes)
			(effects
				(font
					(size 1.27 1.27)
				)
			)
		)
		(property "Value" "SCD01U10V1KX-GP"
			(at -2.8321 -1.7399 90)
			(unlocked yes)
			(layer "F.Fab")
			(hide yes)
			(effects
				(font
					(size 1.016 1.016)
					(thickness 0.1524)
				)
			)
		)
		(property "Device Type" "C0201H13"
			(at -2.8321 -3.2639 90)
			(unlocked yes)
			(layer "F.Fab")
			(hide yes)
			(effects
				(font
					(size 1.016 1.016)
					(thickness 0.1524)
				)
			)
		)
		(duplicate_pad_numbers_are_jumpers no)
		(fp_rect
			(start -0.2794 0.6477)
			(end 0.2794 -0.6477)
			(stroke
				(width 0)
				(type default)
			)
			(fill no)
			(layer "F.CrtYd")
		)
		(fp_rect
			(start -0.2794 0.6477)
			(end 0.2794 -0.6477)
			(stroke
				(width 0)
				(type default)
			)
			(fill no)
			(layer "F.Fab")
		)
		(pad "1" smd custom
			(at 0 -0.2794 90)
			(size 0.0762 0.0762)
			(layers "F.Cu" "F.Mask" "F.Paste")
			(net "3X24_SAS_TX16_P")
			(options
				(clearance outline)
				(anchor circle)
			)
			(primitives
				(gr_poly
					(pts
						(arc
							(start 0.1524 -0.127)
							(mid 0.137521 -0.162921)
							(end 0.1016 -0.1778)
						)
						(arc
							(start -0.1016 -0.1778)
							(mid -0.137521 -0.162921)
							(end -0.1524 -0.127)
						)
						(arc
							(start -0.1524 0.127)
							(mid -0.137521 0.162921)
							(end -0.1016 0.1778)
						)
						(arc
							(start 0.1016 0.1778)
							(mid 0.137521 0.162921)
							(end 0.1524 0.127)
						)
					)
					(width 0)
					(fill yes)
				)
			)
		)
		(pad "2" smd custom
			(at 0 0.2794 90)
			(size 0.0762 0.0762)
			(layers "F.Cu" "F.Mask" "F.Paste")
			(net "SAS_EXP2CONN_TX_P_20")
			(options
				(clearance outline)
				(anchor circle)
			)
			(primitives
				(gr_poly
					(pts
						(arc
							(start 0.1524 -0.127)
							(mid 0.137521 -0.162921)
							(end 0.1016 -0.1778)
						)
						(arc
							(start -0.1016 -0.1778)
							(mid -0.137521 -0.162921)
							(end -0.1524 -0.127)
						)
						(arc
							(start -0.1524 0.127)
							(mid -0.137521 0.162921)
							(end -0.1016 0.1778)
						)
						(arc
							(start 0.1016 0.1778)
							(mid 0.137521 0.162921)
							(end 0.1524 0.127)
						)
					)
					(width 0)
					(fill yes)
				)
			)
		)
	)
)
